(kicad_pcb
	(version 20260206)
	(generator "pcbnew")
	(generator_version "10.0")
	(general
		(thickness 1.6)
		(legacy_teardrops no)
	)
	(paper "A4")
	(title_block
		(title "03242023_DA0F0TMBIJ0_F0T_Motherboard_J_brd_V01_OCP.brd")
		(comment 1 "Grand Teton / footprints 5736-5742 of 6105")
	)
	(layers
		(0 "F.Cu" signal "TOP")
		(4 "In1.Cu" signal "GND")
		(6 "In2.Cu" signal "IN1")
		(8 "In3.Cu" signal "GND1")
		(10 "In4.Cu" signal "IN2")
		(12 "In5.Cu" signal "GND2")
		(14 "In6.Cu" signal "IN3")
		(16 "In7.Cu" signal "GND3")
		(18 "In8.Cu" signal "VCC")
		(20 "In9.Cu" signal "VCC1")
		(22 "In10.Cu" signal "GND4")
		(24 "In11.Cu" signal "IN4")
		(26 "In12.Cu" signal "GND5")
		(28 "In13.Cu" signal "IN5")
		(30 "In14.Cu" signal "GND6")
		(32 "In15.Cu" signal "IN6")
		(34 "In16.Cu" signal "GND7")
		(2 "B.Cu" signal "BOTTOM")
		(9 "F.Adhes" user "F.Adhesive")
		(11 "B.Adhes" user "B.Adhesive")
		(13 "F.Paste" user "Package Geometry/Pastemask Top")
		(15 "B.Paste" user "Package Geometry/Pastemask Bottom")
		(5 "F.SilkS" user "Ref Des/Silkscreen Top")
		(7 "B.SilkS" user "Ref Des/Silkscreen Bottom")
		(1 "F.Mask" user "Board Geometry/Soldermask Top")
		(3 "B.Mask" user "Board Geometry/Soldermask Bottom")
		(17 "Dwgs.User" user "User.Drawings")
		(19 "Cmts.User" user "User.Comments")
		(21 "Eco1.User" user "User.Eco1")
		(23 "Eco2.User" user "User.Eco2")
		(25 "Edge.Cuts" user "Board Geometry/Outline")
		(27 "Margin" user)
		(31 "F.CrtYd" user "Package Geometry/Place Bound Top")
		(29 "B.CrtYd" user "Package Geometry/Place Bound Bottom")
		(35 "F.Fab" user "Ref Des/Assembly Top")
		(33 "B.Fab" user "Ref Des/Assembly Bottom")
	)
	(footprint ""
		(layer "B.Cu")
		(at 433.21478 -50.72888 180)
		(property "Reference" "R4680"
			(at 0 0 0)
			(layer "B.SilkS")
			(hide yes)
			(effects
				(font
					(size 1.27 1.27)
				)
				(justify mirror)
			)
		)
		(property "Value" ""
			(at 0 0 0)
			(layer "B.Fab")
			(effects
				(font
					(size 1.27 1.27)
				)
				(justify mirror)
			)
		)
		(duplicate_pad_numbers_are_jumpers no)
		(fp_line
			(start 0.7874 0.4064)
			(end 0.7874 -0.4064)
			(stroke
				(width 0.1524)
				(type default)
			)
			(layer "B.SilkS")
		)
		(fp_line
			(start 0.7874 -0.4064)
			(end -0.7874 -0.4064)
			(stroke
				(width 0.1524)
				(type default)
			)
			(layer "B.SilkS")
		)
		(fp_line
			(start -0.7874 0.4064)
			(end 0.7874 0.4064)
			(stroke
				(width 0.1524)
				(type default)
			)
			(layer "B.SilkS")
		)
		(fp_line
			(start -0.7874 -0.4064)
			(end -0.7874 0.4064)
			(stroke
				(width 0.1524)
				(type default)
			)
			(layer "B.SilkS")
		)
		(fp_line
			(start 0.67945 0.3048)
			(end 0.67945 -0.305054)
			(stroke
				(width 0.1)
				(type default)
			)
			(layer "B.Fab")
		)
		(fp_line
			(start 0.67945 -0.305054)
			(end 0.12065 -0.305054)
			(stroke
				(width 0.1)
				(type default)
			)
			(layer "B.Fab")
		)
		(fp_line
			(start 0.12065 0.3048)
			(end 0.67945 0.3048)
			(stroke
				(width 0.1)
				(type default)
			)
			(layer "B.Fab")
		)
		(fp_line
			(start 0.12065 0.2794)
			(end 0.12065 0.3048)
			(stroke
				(width 0.1)
				(type default)
			)
			(layer "B.Fab")
		)
		(fp_line
			(start 0.12065 -0.2794)
			(end -0.12065 -0.2794)
			(stroke
				(width 0.1)
				(type default)
			)
			(layer "B.Fab")
		)
		(fp_line
			(start 0.12065 -0.305054)
			(end 0.12065 -0.2794)
			(stroke
				(width 0.1)
				(type default)
			)
			(layer "B.Fab")
		)
		(fp_line
			(start -0.120396 0.3048)
			(end -0.120396 0.2794)
			(stroke
				(width 0.1)
				(type default)
			)
			(layer "B.Fab")
		)
		(fp_line
			(start -0.120396 0.2794)
			(end 0.12065 0.2794)
			(stroke
				(width 0.1)
				(type default)
			)
			(layer "B.Fab")
		)
		(fp_line
			(start -0.12065 -0.2794)
			(end -0.12065 -0.3048)
			(stroke
				(width 0.1)
				(type default)
			)
			(layer "B.Fab")
		)
		(fp_line
			(start -0.12065 -0.3048)
			(end -0.67945 -0.3048)
			(stroke
				(width 0.1)
				(type default)
			)
			(layer "B.Fab")
		)
		(fp_line
			(start -0.67945 0.3048)
			(end -0.120396 0.3048)
			(stroke
				(width 0.1)
				(type default)
			)
			(layer "B.Fab")
		)
		(fp_line
			(start -0.67945 -0.3048)
			(end -0.67945 0.3048)
			(stroke
				(width 0.1)
				(type default)
			)
			(layer "B.Fab")
		)
		(pad "1" smd circle
			(at 0.40005 0)
			(size 0 0)
			(layers "B.Cu" "B.Mask" "B.Paste")
			(net "P12V_AUX")
		)
		(pad "2" smd circle
			(at -0.40005 0)
			(size 0 0)
			(layers "B.Cu" "B.Mask" "B.Paste")
			(net "PWRGD_P5V_N")
		)
	)
	(footprint ""
		(layer "B.Cu")
		(at 116.575586 -333.73568 90)
		(property "Reference" "PC534_P1_3"
			(at 0 0 90)
			(layer "B.SilkS")
			(hide yes)
			(effects
				(font
					(size 1.27 1.27)
				)
				(justify mirror)
			)
		)
		(property "Value" ""
			(at 0 0 90)
			(layer "B.Fab")
			(effects
				(font
					(size 1.27 1.27)
				)
				(justify mirror)
			)
		)
		(duplicate_pad_numbers_are_jumpers no)
		(fp_line
			(start 1.524 -0.762)
			(end -1.524 -0.762)
			(stroke
				(width 0.1524)
				(type default)
			)
			(layer "B.SilkS")
		)
		(fp_line
			(start -1.524 -0.762)
			(end -1.524 0.762)
			(stroke
				(width 0.1524)
				(type default)
			)
			(layer "B.SilkS")
		)
		(fp_line
			(start 1.524 0.762)
			(end 1.524 -0.762)
			(stroke
				(width 0.1524)
				(type default)
			)
			(layer "B.SilkS")
		)
		(fp_line
			(start -1.524 0.762)
			(end 1.524 0.762)
			(stroke
				(width 0.1524)
				(type default)
			)
			(layer "B.SilkS")
		)
		(fp_line
			(start 1.1049 -0.724916)
			(end 1.1049 0.724916)
			(stroke
				(width 0.1)
				(type default)
			)
			(layer "B.Fab")
		)
		(fp_line
			(start -1.1049 -0.724916)
			(end 1.1049 -0.724916)
			(stroke
				(width 0.1)
				(type default)
			)
			(layer "B.Fab")
		)
		(fp_line
			(start 1.1049 0.724916)
			(end -1.1049 0.724916)
			(stroke
				(width 0.1)
				(type default)
			)
			(layer "B.Fab")
		)
		(fp_line
			(start -1.1049 0.724916)
			(end -1.1049 -0.724916)
			(stroke
				(width 0.1)
				(type default)
			)
			(layer "B.Fab")
		)
		(pad "1" smd rect
			(at 0.889 0 90)
			(size 1.016 1.27)
			(layers "B.Cu" "B.Mask" "B.Paste")
			(net "SW_P12V_PVCCIN_CPU1_FLT")
		)
		(pad "2" smd rect
			(at -0.889 0 90)
			(size 1.016 1.27)
			(layers "B.Cu" "B.Mask" "B.Paste")
			(net "GND")
		)
	)
	(footprint ""
		(layer "B.Cu")
		(at 74.850498 -179.34178 -90)
		(property "Reference" "R298"
			(at 0 0 90)
			(layer "B.SilkS")
			(hide yes)
			(effects
				(font
					(size 1.27 1.27)
				)
				(justify mirror)
			)
		)
		(property "Value" ""
			(at 0 0 90)
			(layer "B.Fab")
			(effects
				(font
					(size 1.27 1.27)
				)
				(justify mirror)
			)
		)
		(duplicate_pad_numbers_are_jumpers no)
		(fp_line
			(start -0.7874 0.4064)
			(end 0.7874 0.4064)
			(stroke
				(width 0.1524)
				(type default)
			)
			(layer "B.SilkS")
		)
		(fp_line
			(start 0.7874 0.4064)
			(end 0.7874 -0.4064)
			(stroke
				(width 0.1524)
				(type default)
			)
			(layer "B.SilkS")
		)
		(fp_line
			(start -0.7874 -0.4064)
			(end -0.7874 0.4064)
			(stroke
				(width 0.1524)
				(type default)
			)
			(layer "B.SilkS")
		)
		(fp_line
			(start 0.7874 -0.4064)
			(end -0.7874 -0.4064)
			(stroke
				(width 0.1524)
				(type default)
			)
			(layer "B.SilkS")
		)
		(fp_line
			(start -0.67945 0.3048)
			(end -0.120396 0.3048)
			(stroke
				(width 0.1)
				(type default)
			)
			(layer "B.Fab")
		)
		(fp_line
			(start -0.120396 0.3048)
			(end -0.120396 0.2794)
			(stroke
				(width 0.1)
				(type default)
			)
			(layer "B.Fab")
		)
		(fp_line
			(start 0.12065 0.3048)
			(end 0.67945 0.3048)
			(stroke
				(width 0.1)
				(type default)
			)
			(layer "B.Fab")
		)
		(fp_line
			(start 0.67945 0.3048)
			(end 0.67945 -0.305054)
			(stroke
				(width 0.1)
				(type default)
			)
			(layer "B.Fab")
		)
		(fp_line
			(start -0.120396 0.2794)
			(end 0.12065 0.2794)
			(stroke
				(width 0.1)
				(type default)
			)
			(layer "B.Fab")
		)
		(fp_line
			(start 0.12065 0.2794)
			(end 0.12065 0.3048)
			(stroke
				(width 0.1)
				(type default)
			)
			(layer "B.Fab")
		)
		(fp_line
			(start -0.12065 -0.2794)
			(end -0.12065 -0.3048)
			(stroke
				(width 0.1)
				(type default)
			)
			(layer "B.Fab")
		)
		(fp_line
			(start 0.12065 -0.2794)
			(end -0.12065 -0.2794)
			(stroke
				(width 0.1)
				(type default)
			)
			(layer "B.Fab")
		)
		(fp_line
			(start -0.67945 -0.3048)
			(end -0.67945 0.3048)
			(stroke
				(width 0.1)
				(type default)
			)
			(layer "B.Fab")
		)
		(fp_line
			(start -0.12065 -0.3048)
			(end -0.67945 -0.3048)
			(stroke
				(width 0.1)
				(type default)
			)
			(layer "B.Fab")
		)
		(fp_line
			(start 0.12065 -0.305054)
			(end 0.12065 -0.2794)
			(stroke
				(width 0.1)
				(type default)
			)
			(layer "B.Fab")
		)
		(fp_line
			(start 0.67945 -0.305054)
			(end 0.12065 -0.305054)
			(stroke
				(width 0.1)
				(type default)
			)
			(layer "B.Fab")
		)
		(pad "1" smd circle
			(at 0.40005 0 90)
			(size 0 0)
			(layers "B.Cu" "B.Mask" "B.Paste")
			(net "PVNN_TERM_CPU1")
		)
		(pad "2" smd circle
			(at -0.40005 0 90)
			(size 0 0)
			(layers "B.Cu" "B.Mask" "B.Paste")
			(net "H_CPU_CATERR_LVC1_R_N")
		)
	)
	(footprint ""
		(layer "B.Cu")
		(at 170.20032 -13.762228 90)
		(property "Reference" "R4536"
			(at 0 0 90)
			(layer "B.SilkS")
			(hide yes)
			(effects
				(font
					(size 1.27 1.27)
				)
				(justify mirror)
			)
		)
		(property "Value" ""
			(at 0 0 90)
			(layer "B.Fab")
			(effects
				(font
					(size 1.27 1.27)
				)
				(justify mirror)
			)
		)
		(duplicate_pad_numbers_are_jumpers no)
		(fp_line
			(start 0.7874 -0.4064)
			(end -0.7874 -0.4064)
			(stroke
				(width 0.1524)
				(type default)
			)
			(layer "B.SilkS")
		)
		(fp_line
			(start -0.7874 -0.4064)
			(end -0.7874 0.14732)
			(stroke
				(width 0.1524)
				(type default)
			)
			(layer "B.SilkS")
		)
		(fp_line
			(start 0.7874 0.20574)
			(end 0.7874 -0.4064)
			(stroke
				(width 0.1524)
				(type default)
			)
			(layer "B.SilkS")
		)
		(fp_line
			(start -0.10668 0.4064)
			(end 0.40386 0.4064)
			(stroke
				(width 0.1524)
				(type default)
			)
			(layer "B.SilkS")
		)
		(fp_line
			(start 0.67945 -0.305054)
			(end 0.12065 -0.305054)
			(stroke
				(width 0.1)
				(type default)
			)
			(layer "B.Fab")
		)
		(fp_line
			(start 0.12065 -0.305054)
			(end 0.12065 -0.2794)
			(stroke
				(width 0.1)
				(type default)
			)
			(layer "B.Fab")
		)
		(fp_line
			(start -0.12065 -0.3048)
			(end -0.67945 -0.3048)
			(stroke
				(width 0.1)
				(type default)
			)
			(layer "B.Fab")
		)
		(fp_line
			(start -0.67945 -0.3048)
			(end -0.67945 0.3048)
			(stroke
				(width 0.1)
				(type default)
			)
			(layer "B.Fab")
		)
		(fp_line
			(start 0.12065 -0.2794)
			(end -0.12065 -0.2794)
			(stroke
				(width 0.1)
				(type default)
			)
			(layer "B.Fab")
		)
		(fp_line
			(start -0.12065 -0.2794)
			(end -0.12065 -0.3048)
			(stroke
				(width 0.1)
				(type default)
			)
			(layer "B.Fab")
		)
		(fp_line
			(start 0.12065 0.2794)
			(end 0.12065 0.3048)
			(stroke
				(width 0.1)
				(type default)
			)
			(layer "B.Fab")
		)
		(fp_line
			(start -0.120396 0.2794)
			(end 0.12065 0.2794)
			(stroke
				(width 0.1)
				(type default)
			)
			(layer "B.Fab")
		)
		(fp_line
			(start 0.67945 0.3048)
			(end 0.67945 -0.305054)
			(stroke
				(width 0.1)
				(type default)
			)
			(layer "B.Fab")
		)
		(fp_line
			(start 0.12065 0.3048)
			(end 0.67945 0.3048)
			(stroke
				(width 0.1)
				(type default)
			)
			(layer "B.Fab")
		)
		(fp_line
			(start -0.120396 0.3048)
			(end -0.120396 0.2794)
			(stroke
				(width 0.1)
				(type default)
			)
			(layer "B.Fab")
		)
		(fp_line
			(start -0.67945 0.3048)
			(end -0.120396 0.3048)
			(stroke
				(width 0.1)
				(type default)
			)
			(layer "B.Fab")
		)
		(pad "1" smd circle
			(at 0.40005 0 270)
			(size 0 0)
			(layers "B.Cu" "B.Mask" "B.Paste")
			(net "CLK_100M_BMC_P3E_DN")
		)
		(pad "2" smd circle
			(at -0.40005 0 270)
			(size 0 0)
			(layers "B.Cu" "B.Mask" "B.Paste")
			(net "CLK_100M_BMC_P3E_DN_R")
		)
	)
	(footprint ""
		(layer "B.Cu")
		(at 367.009934 -237.709202 -90)
		(property "Reference" "C532"
			(at 0 0 90)
			(layer "B.SilkS")
			(hide yes)
			(effects
				(font
					(size 1.27 1.27)
				)
				(justify mirror)
			)
		)
		(property "Value" ""
			(at 0 0 90)
			(layer "B.Fab")
			(effects
				(font
					(size 1.27 1.27)
				)
				(justify mirror)
			)
		)
		(duplicate_pad_numbers_are_jumpers no)
		(fp_line
			(start -1.2954 0.5842)
			(end 1.2954 0.5842)
			(stroke
				(width 0.1524)
				(type default)
			)
			(layer "B.SilkS")
		)
		(fp_line
			(start 1.2954 0.5842)
			(end 1.2954 -0.5842)
			(stroke
				(width 0.1524)
				(type default)
			)
			(layer "B.SilkS")
		)
		(fp_line
			(start -1.2954 -0.5842)
			(end -1.2954 0.5842)
			(stroke
				(width 0.1524)
				(type default)
			)
			(layer "B.SilkS")
		)
		(fp_line
			(start 0 -0.5842)
			(end 0 0.5842)
			(stroke
				(width 0.1524)
				(type default)
			)
			(layer "B.SilkS")
		)
		(fp_line
			(start 1.2954 -0.5842)
			(end -1.2954 -0.5842)
			(stroke
				(width 0.1524)
				(type default)
			)
			(layer "B.SilkS")
		)
		(fp_line
			(start -0.8636 0.4572)
			(end 0.8636 0.4572)
			(stroke
				(width 0.1)
				(type default)
			)
			(layer "B.Fab")
		)
		(fp_line
			(start 0.8636 0.4572)
			(end 0.8636 0.4064)
			(stroke
				(width 0.1)
				(type default)
			)
			(layer "B.Fab")
		)
		(fp_line
			(start -1.1938 0.4064)
			(end -0.8636 0.4064)
			(stroke
				(width 0.1)
				(type default)
			)
			(layer "B.Fab")
		)
		(fp_line
			(start -0.8636 0.4064)
			(end -0.8636 0.4572)
			(stroke
				(width 0.1)
				(type default)
			)
			(layer "B.Fab")
		)
		(fp_line
			(start 0.8636 0.4064)
			(end 1.1938 0.4064)
			(stroke
				(width 0.1)
				(type default)
			)
			(layer "B.Fab")
		)
		(fp_line
			(start 1.1938 0.4064)
			(end 1.1938 -0.4064)
			(stroke
				(width 0.1)
				(type default)
			)
			(layer "B.Fab")
		)
		(fp_line
			(start -1.1938 -0.4064)
			(end -1.1938 0.4064)
			(stroke
				(width 0.1)
				(type default)
			)
			(layer "B.Fab")
		)
		(fp_line
			(start -0.8636 -0.4064)
			(end -1.1938 -0.4064)
			(stroke
				(width 0.1)
				(type default)
			)
			(layer "B.Fab")
		)
		(fp_line
			(start 0.8636 -0.4064)
			(end 0.8636 -0.4572)
			(stroke
				(width 0.1)
				(type default)
			)
			(layer "B.Fab")
		)
		(fp_line
			(start 1.1938 -0.4064)
			(end 0.8636 -0.4064)
			(stroke
				(width 0.1)
				(type default)
			)
			(layer "B.Fab")
		)
		(fp_line
			(start -0.8636 -0.4572)
			(end -0.8636 -0.4064)
			(stroke
				(width 0.1)
				(type default)
			)
			(layer "B.Fab")
		)
		(fp_line
			(start 0.8636 -0.4572)
			(end -0.8636 -0.4572)
			(stroke
				(width 0.1)
				(type default)
			)
			(layer "B.Fab")
		)
		(pad "1" smd rect
			(at 0.7366 0 180)
			(size 0.7112 0.8128)
			(layers "B.Cu" "B.Mask" "B.Paste")
			(net "PVCCINFAON_CPU0")
		)
		(pad "2" smd rect
			(at -0.7366 0 180)
			(size 0.7112 0.8128)
			(layers "B.Cu" "B.Mask" "B.Paste")
			(net "GND")
		)
	)
	(footprint ""
		(layer "B.Cu")
		(at 92.09405 -337.145884 90)
		(property "Reference" "PC511_P1_6"
			(at 0 0 90)
			(layer "B.SilkS")
			(hide yes)
			(effects
				(font
					(size 1.27 1.27)
				)
				(justify mirror)
			)
		)
		(property "Value" ""
			(at 0 0 90)
			(layer "B.Fab")
			(effects
				(font
					(size 1.27 1.27)
				)
				(justify mirror)
			)
		)
		(duplicate_pad_numbers_are_jumpers no)
		(fp_line
			(start 1.524 -0.762)
			(end -1.524 -0.762)
			(stroke
				(width 0.1524)
				(type default)
			)
			(layer "B.SilkS")
		)
		(fp_line
			(start -1.524 -0.762)
			(end -1.524 0.762)
			(stroke
				(width 0.1524)
				(type default)
			)
			(layer "B.SilkS")
		)
		(fp_line
			(start 1.524 0.762)
			(end 1.524 -0.762)
			(stroke
				(width 0.1524)
				(type default)
			)
			(layer "B.SilkS")
		)
		(fp_line
			(start -1.524 0.762)
			(end 1.524 0.762)
			(stroke
				(width 0.1524)
				(type default)
			)
			(layer "B.SilkS")
		)
		(fp_line
			(start 1.1049 -0.724916)
			(end 1.1049 0.724916)
			(stroke
				(width 0.1)
				(type default)
			)
			(layer "B.Fab")
		)
		(fp_line
			(start -1.1049 -0.724916)
			(end 1.1049 -0.724916)
			(stroke
				(width 0.1)
				(type default)
			)
			(layer "B.Fab")
		)
		(fp_line
			(start 1.1049 0.724916)
			(end -1.1049 0.724916)
			(stroke
				(width 0.1)
				(type default)
			)
			(layer "B.Fab")
		)
		(fp_line
			(start -1.1049 0.724916)
			(end -1.1049 -0.724916)
			(stroke
				(width 0.1)
				(type default)
			)
			(layer "B.Fab")
		)
		(pad "1" smd rect
			(at 0.889 0 90)
			(size 1.016 1.27)
			(layers "B.Cu" "B.Mask" "B.Paste")
			(net "SW_P12V_PVCCIN_CPU1_FLT")
		)
		(pad "2" smd rect
			(at -0.889 0 90)
			(size 1.016 1.27)
			(layers "B.Cu" "B.Mask" "B.Paste")
			(net "GND")
		)
	)
	(footprint ""
		(layer "B.Cu")
		(at 451.549516 -10.634726 90)
		(property "Reference" "R421"
			(at 0 0 90)
			(layer "B.SilkS")
			(hide yes)
			(effects
				(font
					(size 1.27 1.27)
				)
				(justify mirror)
			)
		)
		(property "Value" ""
			(at 0 0 90)
			(layer "B.Fab")
			(effects
				(font
					(size 1.27 1.27)
				)
				(justify mirror)
			)
		)
		(duplicate_pad_numbers_are_jumpers no)
		(fp_line
			(start 0.7874 -0.4064)
			(end -0.7874 -0.4064)
			(stroke
				(width 0.1524)
				(type default)
			)
			(layer "B.SilkS")
		)
		(fp_line
			(start -0.7874 -0.4064)
			(end -0.7874 0.4064)
			(stroke
				(width 0.1524)
				(type default)
			)
			(layer "B.SilkS")
		)
		(fp_line
			(start 0.7874 0.4064)
			(end 0.7874 -0.4064)
			(stroke
				(width 0.1524)
				(type default)
			)
			(layer "B.SilkS")
		)
		(fp_line
			(start -0.7874 0.4064)
			(end 0.7874 0.4064)
			(stroke
				(width 0.1524)
				(type default)
			)
			(layer "B.SilkS")
		)
		(fp_line
			(start 0.67945 -0.305054)
			(end 0.12065 -0.305054)
			(stroke
				(width 0.1)
				(type default)
			)
			(layer "B.Fab")
		)
		(fp_line
			(start 0.12065 -0.305054)
			(end 0.12065 -0.2794)
			(stroke
				(width 0.1)
				(type default)
			)
			(layer "B.Fab")
		)
		(fp_line
			(start -0.12065 -0.3048)
			(end -0.67945 -0.3048)
			(stroke
				(width 0.1)
				(type default)
			)
			(layer "B.Fab")
		)
		(fp_line
			(start -0.67945 -0.3048)
			(end -0.67945 0.3048)
			(stroke
				(width 0.1)
				(type default)
			)
			(layer "B.Fab")
		)
		(fp_line
			(start 0.12065 -0.2794)
			(end -0.12065 -0.2794)
			(stroke
				(width 0.1)
				(type default)
			)
			(layer "B.Fab")
		)
		(fp_line
			(start -0.12065 -0.2794)
			(end -0.12065 -0.3048)
			(stroke
				(width 0.1)
				(type default)
			)
			(layer "B.Fab")
		)
		(fp_line
			(start 0.12065 0.2794)
			(end 0.12065 0.3048)
			(stroke
				(width 0.1)
				(type default)
			)
			(layer "B.Fab")
		)
		(fp_line
			(start -0.120396 0.2794)
			(end 0.12065 0.2794)
			(stroke
				(width 0.1)
				(type default)
			)
			(layer "B.Fab")
		)
		(fp_line
			(start 0.67945 0.3048)
			(end 0.67945 -0.305054)
			(stroke
				(width 0.1)
				(type default)
			)
			(layer "B.Fab")
		)
		(fp_line
			(start 0.12065 0.3048)
			(end 0.67945 0.3048)
			(stroke
				(width 0.1)
				(type default)
			)
			(layer "B.Fab")
		)
		(fp_line
			(start -0.120396 0.3048)
			(end -0.120396 0.2794)
			(stroke
				(width 0.1)
				(type default)
			)
			(layer "B.Fab")
		)
		(fp_line
			(start -0.67945 0.3048)
			(end -0.120396 0.3048)
			(stroke
				(width 0.1)
				(type default)
			)
			(layer "B.Fab")
		)
		(pad "1" smd circle
			(at 0.40005 0 270)
			(size 0 0)
			(layers "B.Cu" "B.Mask" "B.Paste")
			(net "SGPIO_OCP_SFF_DATAIN")
		)
		(pad "2" smd circle
			(at -0.40005 0 270)
			(size 0 0)
			(layers "B.Cu" "B.Mask" "B.Paste")
			(net "P3V3_OCP_SFF")
		)
	)
)
